(kicad_pcb
	(version 20260206)
	(generator "pcbnew")
	(generator_version "10.0")
	(general
		(thickness 1.6)
		(legacy_teardrops no)
	)
	(paper "A4")
	(title_block
		(title "Bryce Canyon_IOM_IOC_16318-2_OCP.brd")
		(comment 1 "Bryce Canyon / footprints 137-144 of 1605")
	)
	(layers
		(0 "F.Cu" signal "TOP")
		(4 "In1.Cu" signal "L2GND")
		(6 "In2.Cu" signal "L3")
		(8 "In3.Cu" signal "L4VCC")
		(10 "In4.Cu" signal "L5VCC")
		(12 "In5.Cu" signal "L6")
		(14 "In6.Cu" signal "L7GND")
		(2 "B.Cu" signal "BOTTOM")
		(9 "F.Adhes" user "F.Adhesive")
		(11 "B.Adhes" user "B.Adhesive")
		(13 "F.Paste" user "Package Geometry/Pastemask Top")
		(15 "B.Paste" user "Package Geometry/Pastemask Bottom")
		(5 "F.SilkS" user "Ref Des/Silkscreen Top")
		(7 "B.SilkS" user "Ref Des/Silkscreen Bottom")
		(1 "F.Mask" user "Board Geometry/Soldermask Top")
		(3 "B.Mask" user "Board Geometry/Soldermask Bottom")
		(17 "Dwgs.User" user "User.Drawings")
		(19 "Cmts.User" user "User.Comments")
		(21 "Eco1.User" user "User.Eco1")
		(23 "Eco2.User" user "User.Eco2")
		(25 "Edge.Cuts" user "Board Geometry/Outline")
		(27 "Margin" user)
		(31 "F.CrtYd" user "Package Geometry/Place Bound Top")
		(29 "B.CrtYd" user "Package Geometry/Place Bound Bottom")
		(35 "F.Fab" user "Ref Des/Assembly Top")
		(33 "B.Fab" user "Ref Des/Assembly Bottom")
	)
	(footprint ""
		(layer "F.Cu")
		(at 199.5424 -48.2854 180)
		(property "Reference" "R633"
			(at 0 0 180)
			(layer "F.SilkS")
			(hide yes)
			(effects
				(font
					(size 1.27 1.27)
				)
			)
		)
		(property "Value" "4K7R2F-GP"
			(at 0.064008 -3.993896 180)
			(unlocked yes)
			(layer "F.Fab")
			(hide yes)
			(effects
				(font
					(size 1.016 1.016)
					(thickness 0.1524)
				)
			)
		)
		(property "Device Type" "R402H16"
			(at 0.064008 -5.517896 180)
			(unlocked yes)
			(layer "F.Fab")
			(hide yes)
			(effects
				(font
					(size 1.016 1.016)
					(thickness 0.1524)
				)
			)
		)
		(duplicate_pad_numbers_are_jumpers no)
		(fp_line
			(start 0.508 -0.9398)
			(end -0.508 -0.9398)
			(stroke
				(width 0.1524)
				(type default)
			)
			(layer "F.SilkS")
		)
		(fp_line
			(start -0.508 -0.9398)
			(end -0.508 0.9398)
			(stroke
				(width 0.1524)
				(type default)
			)
			(layer "F.SilkS")
		)
		(fp_rect
			(start -0.508 0.9398)
			(end 0.508 -0.9398)
			(stroke
				(width 0)
				(type default)
			)
			(fill no)
			(layer "F.CrtYd")
		)
		(fp_rect
			(start -0.508 0.9398)
			(end 0.508 -0.9398)
			(stroke
				(width 0)
				(type default)
			)
			(fill no)
			(layer "F.Fab")
		)
		(pad "1" smd custom
			(at 0 -0.4445 180)
			(size 0.1397 0.1397)
			(layers "F.Cu" "F.Mask" "F.Paste")
			(net "P1V8")
			(options
				(clearance outline)
				(anchor circle)
			)
			(primitives
				(gr_poly
					(pts
						(arc
							(start -0.1778 -0.2794)
							(mid -0.249642 -0.249642)
							(end -0.2794 -0.1778)
						)
						(arc
							(start -0.2794 0.1778)
							(mid -0.249642 0.249642)
							(end -0.1778 0.2794)
						)
						(arc
							(start 0.1778 0.2794)
							(mid 0.249642 0.249642)
							(end 0.2794 0.1778)
						)
						(arc
							(start 0.2794 -0.1778)
							(mid 0.249642 -0.249642)
							(end 0.1778 -0.2794)
						)
					)
					(width 0)
					(fill yes)
				)
			)
		)
		(pad "2" smd custom
			(at 0 0.4445 180)
			(size 0.1397 0.1397)
			(layers "F.Cu" "F.Mask" "F.Paste")
			(net "ICE0_TRST#")
			(options
				(clearance outline)
				(anchor circle)
			)
			(primitives
				(gr_poly
					(pts
						(arc
							(start -0.1778 -0.2794)
							(mid -0.249642 -0.249642)
							(end -0.2794 -0.1778)
						)
						(arc
							(start -0.2794 0.1778)
							(mid -0.249642 0.249642)
							(end -0.1778 0.2794)
						)
						(arc
							(start 0.1778 0.2794)
							(mid 0.249642 0.249642)
							(end 0.2794 0.1778)
						)
						(arc
							(start 0.2794 -0.1778)
							(mid 0.249642 -0.249642)
							(end 0.1778 -0.2794)
						)
					)
					(width 0)
					(fill yes)
				)
			)
		)
	)
	(footprint ""
		(layer "F.Cu")
		(at 53.96103 -166.443152 180)
		(property "Reference" "C519"
			(at 0 0 180)
			(layer "F.SilkS")
			(hide yes)
			(effects
				(font
					(size 1.27 1.27)
				)
			)
		)
		(property "Value" "SCD1U25V2KX-2-GP"
			(at 1.1811 -2.7051 180)
			(unlocked yes)
			(layer "F.Fab")
			(hide yes)
			(effects
				(font
					(size 1.016 1.016)
					(thickness 0.1524)
				)
			)
		)
		(property "Device Type" "C402H22"
			(at 1.1811 -4.2291 180)
			(unlocked yes)
			(layer "F.Fab")
			(hide yes)
			(effects
				(font
					(size 1.016 1.016)
					(thickness 0.1524)
				)
			)
		)
		(duplicate_pad_numbers_are_jumpers no)
		(fp_rect
			(start -0.4318 0.9525)
			(end 0.4318 -0.9525)
			(stroke
				(width 0)
				(type default)
			)
			(fill no)
			(layer "F.CrtYd")
		)
		(fp_rect
			(start -0.4318 0.9525)
			(end 0.4318 -0.9525)
			(stroke
				(width 0)
				(type default)
			)
			(fill no)
			(layer "F.Fab")
		)
		(pad "1" smd custom
			(at 0 -0.4445 180)
			(size 0.1524 0.1524)
			(layers "F.Cu" "F.Mask" "F.Paste")
			(net "ADC_P1V2_STBY")
			(options
				(clearance outline)
				(anchor circle)
			)
			(primitives
				(gr_poly
					(pts
						(arc
							(start 0.3048 -0.2032)
							(mid 0.275042 -0.275042)
							(end 0.2032 -0.3048)
						)
						(arc
							(start -0.2032 -0.3048)
							(mid -0.275042 -0.275042)
							(end -0.3048 -0.2032)
						)
						(arc
							(start -0.3048 0.2032)
							(mid -0.275042 0.275042)
							(end -0.2032 0.3048)
						)
						(arc
							(start 0.2032 0.3048)
							(mid 0.275042 0.275042)
							(end 0.3048 0.2032)
						)
					)
					(width 0)
					(fill yes)
				)
			)
		)
		(pad "2" smd custom
			(at 0 0.4445 180)
			(size 0.1524 0.1524)
			(layers "F.Cu" "F.Mask" "F.Paste")
			(net "GND")
			(options
				(clearance outline)
				(anchor circle)
			)
			(primitives
				(gr_poly
					(pts
						(arc
							(start 0.3048 -0.2032)
							(mid 0.275042 -0.275042)
							(end 0.2032 -0.3048)
						)
						(arc
							(start -0.2032 -0.3048)
							(mid -0.275042 -0.275042)
							(end -0.3048 -0.2032)
						)
						(arc
							(start -0.3048 0.2032)
							(mid -0.275042 0.275042)
							(end -0.2032 0.3048)
						)
						(arc
							(start 0.2032 0.3048)
							(mid 0.275042 0.275042)
							(end 0.3048 0.2032)
						)
					)
					(width 0)
					(fill yes)
				)
			)
		)
	)
	(footprint ""
		(layer "F.Cu")
		(at 46.035976 -116.780818 -90)
		(property "Reference" "R86"
			(at 0 0 270)
			(layer "F.SilkS")
			(hide yes)
			(effects
				(font
					(size 1.27 1.27)
				)
			)
		)
		(property "Value" "2K2R2J-2-GP"
			(at 0.064008 -3.993896 270)
			(unlocked yes)
			(layer "F.Fab")
			(hide yes)
			(effects
				(font
					(size 1.016 1.016)
					(thickness 0.1524)
				)
			)
		)
		(property "Device Type" "R402H16"
			(at 0.064008 -5.517896 270)
			(unlocked yes)
			(layer "F.Fab")
			(hide yes)
			(effects
				(font
					(size 1.016 1.016)
					(thickness 0.1524)
				)
			)
		)
		(duplicate_pad_numbers_are_jumpers no)
		(fp_line
			(start -0.508 -0.9398)
			(end -0.508 0.9398)
			(stroke
				(width 0.1524)
				(type default)
			)
			(layer "F.SilkS")
		)
		(fp_line
			(start 0.508 -0.9398)
			(end -0.508 -0.9398)
			(stroke
				(width 0.1524)
				(type default)
			)
			(layer "F.SilkS")
		)
		(fp_rect
			(start -0.508 0.9398)
			(end 0.508 -0.9398)
			(stroke
				(width 0)
				(type default)
			)
			(fill no)
			(layer "F.CrtYd")
		)
		(fp_rect
			(start -0.508 0.9398)
			(end 0.508 -0.9398)
			(stroke
				(width 0)
				(type default)
			)
			(fill no)
			(layer "F.Fab")
		)
		(pad "1" smd custom
			(at 0 -0.4445 270)
			(size 0.1397 0.1397)
			(layers "F.Cu" "F.Mask" "F.Paste")
			(net "P3V3_STBY")
			(options
				(clearance outline)
				(anchor circle)
			)
			(primitives
				(gr_poly
					(pts
						(arc
							(start -0.1778 -0.2794)
							(mid -0.249642 -0.249642)
							(end -0.2794 -0.1778)
						)
						(arc
							(start -0.2794 0.1778)
							(mid -0.249642 0.249642)
							(end -0.1778 0.2794)
						)
						(arc
							(start 0.1778 0.2794)
							(mid 0.249642 0.249642)
							(end 0.2794 0.1778)
						)
						(arc
							(start 0.2794 -0.1778)
							(mid 0.249642 -0.249642)
							(end 0.1778 -0.2794)
						)
					)
					(width 0)
					(fill yes)
				)
			)
		)
		(pad "2" smd custom
			(at 0 0.4445 270)
			(size 0.1397 0.1397)
			(layers "F.Cu" "F.Mask" "F.Paste")
			(net "FLA0_SPI_HOLD_N")
			(options
				(clearance outline)
				(anchor circle)
			)
			(primitives
				(gr_poly
					(pts
						(arc
							(start -0.1778 -0.2794)
							(mid -0.249642 -0.249642)
							(end -0.2794 -0.1778)
						)
						(arc
							(start -0.2794 0.1778)
							(mid -0.249642 0.249642)
							(end -0.1778 0.2794)
						)
						(arc
							(start 0.1778 0.2794)
							(mid 0.249642 0.249642)
							(end 0.2794 0.1778)
						)
						(arc
							(start 0.2794 -0.1778)
							(mid 0.249642 -0.249642)
							(end 0.1778 -0.2794)
						)
					)
					(width 0)
					(fill yes)
				)
			)
		)
	)
	(footprint ""
		(layer "F.Cu")
		(at 172.942504 -142.171166 -90)
		(property "Reference" "C155"
			(at 0 0 270)
			(layer "F.SilkS")
			(hide yes)
			(effects
				(font
					(size 1.27 1.27)
				)
			)
		)
		(property "Value" "SC10U16V5KX-7-GP-U"
			(at -0.0762 -6.1214 270)
			(unlocked yes)
			(layer "F.Fab")
			(hide yes)
			(effects
				(font
					(size 1.016 1.016)
					(thickness 0.1524)
				)
			)
		)
		(property "Device Type" "C805H58"
			(at -0.0762 -8.1534 270)
			(unlocked yes)
			(layer "F.Fab")
			(hide yes)
			(effects
				(font
					(size 1.016 1.016)
					(thickness 0.1524)
				)
			)
		)
		(duplicate_pad_numbers_are_jumpers no)
		(fp_line
			(start 0.635 0)
			(end -0.635 0)
			(stroke
				(width 0.508)
				(type default)
			)
			(layer "F.SilkS")
		)
		(fp_rect
			(start -0.9652 1.778)
			(end 0.9652 -1.778)
			(stroke
				(width 0)
				(type default)
			)
			(fill no)
			(layer "F.CrtYd")
		)
		(fp_poly
			(pts
				(xy -0.9652 -1.778) (xy 0.9652 -1.778) (xy 0.9652 1.778) (xy -0.9652 1.778)
			)
			(stroke
				(width 0)
				(type default)
			)
			(fill no)
			(layer "F.Fab")
		)
		(pad "1" smd rect
			(at 0 -0.9652 270)
			(size 1.397 1.143)
			(layers "F.Cu" "F.Mask" "F.Paste")
			(net "P12V_STBY_VIN_PU1")
		)
		(pad "2" smd rect
			(at 0 0.9652 270)
			(size 1.397 1.143)
			(layers "F.Cu" "F.Mask" "F.Paste")
			(net "GND")
		)
	)
	(footprint ""
		(layer "F.Cu")
		(at 78.122018 -70.952868 90)
		(property "Reference" "VIA1"
			(at 0 0 90)
			(layer "F.SilkS")
			(hide yes)
			(effects
				(font
					(size 1.27 1.27)
				)
			)
		)
		(property "Value" "85OHM-8L-1D6MM-L16L18-GP"
			(at 4.064 0.6096 90)
			(unlocked yes)
			(layer "F.Fab")
			(hide yes)
			(effects
				(font
					(size 1.016 1.016)
					(thickness 0.1524)
				)
			)
		)
		(property "Device Type" "VIA-PCIE-4P-368076"
			(at 4.064 -0.9144 90)
			(unlocked yes)
			(layer "F.Fab")
			(hide yes)
			(effects
				(font
					(size 1.016 1.016)
					(thickness 0.1524)
				)
			)
		)
		(duplicate_pad_numbers_are_jumpers no)
		(fp_rect
			(start -1.8415 0.381)
			(end 1.8415 -0.381)
			(stroke
				(width 0)
				(type default)
			)
			(fill no)
			(layer "F.CrtYd")
		)
		(fp_rect
			(start -1.8415 0.381)
			(end 1.8415 -0.381)
			(stroke
				(width 0)
				(type default)
			)
			(fill no)
			(layer "F.Fab")
		)
		(pad "1" thru_hole circle
			(at -1.4605 0 90)
			(size 0.508 0.508)
			(drill 0.254)
			(layers "*.Cu" "*.Mask")
			(remove_unused_layers no)
			(net "GND")
			(clearance 0.127)
			(thermal_gap 0.127)
		)
		(pad "2" thru_hole circle
			(at -0.4445 0 90)
			(size 0.508 0.508)
			(drill 0.254)
			(layers "*.Cu" "*.Mask")
			(remove_unused_layers no)
			(net "PCIE_COMP_TO_IOM_16_DP")
			(clearance 0.127)
			(thermal_gap 0.127)
		)
		(pad "3" thru_hole circle
			(at 0.4445 0 90)
			(size 0.508 0.508)
			(drill 0.254)
			(layers "*.Cu" "*.Mask")
			(remove_unused_layers no)
			(net "PCIE_COMP_TO_IOM_16_DN")
			(clearance 0.127)
			(thermal_gap 0.127)
		)
		(pad "4" thru_hole circle
			(at 1.4605 0 90)
			(size 0.508 0.508)
			(drill 0.254)
			(layers "*.Cu" "*.Mask")
			(remove_unused_layers no)
			(net "GND")
			(clearance 0.127)
			(thermal_gap 0.127)
		)
	)
	(footprint ""
		(layer "F.Cu")
		(at 28.194 -153.67 -90)
		(property "Reference" "R771"
			(at 0 0 270)
			(layer "F.SilkS")
			(hide yes)
			(effects
				(font
					(size 1.27 1.27)
				)
			)
		)
		(property "Value" "0R2J-2-GP"
			(at 0.064008 -3.993896 270)
			(unlocked yes)
			(layer "F.Fab")
			(hide yes)
			(effects
				(font
					(size 1.016 1.016)
					(thickness 0.1524)
				)
			)
		)
		(property "Device Type" "R402H16"
			(at 0.064008 -5.517896 270)
			(unlocked yes)
			(layer "F.Fab")
			(hide yes)
			(effects
				(font
					(size 1.016 1.016)
					(thickness 0.1524)
				)
			)
		)
		(duplicate_pad_numbers_are_jumpers no)
		(fp_line
			(start -0.508 -0.9398)
			(end -0.508 0.9398)
			(stroke
				(width 0.1524)
				(type default)
			)
			(layer "F.SilkS")
		)
		(fp_line
			(start 0.508 -0.9398)
			(end -0.508 -0.9398)
			(stroke
				(width 0.1524)
				(type default)
			)
			(layer "F.SilkS")
		)
		(fp_rect
			(start -0.508 0.9398)
			(end 0.508 -0.9398)
			(stroke
				(width 0)
				(type default)
			)
			(fill no)
			(layer "F.CrtYd")
		)
		(fp_rect
			(start -0.508 0.9398)
			(end 0.508 -0.9398)
			(stroke
				(width 0)
				(type default)
			)
			(fill no)
			(layer "F.Fab")
		)
		(pad "1" smd custom
			(at 0 -0.4445 270)
			(size 0.1397 0.1397)
			(layers "F.Cu" "F.Mask" "F.Paste")
			(net "DEBUG_GPIO_BMC_R_4")
			(options
				(clearance outline)
				(anchor circle)
			)
			(primitives
				(gr_poly
					(pts
						(arc
							(start -0.1778 -0.2794)
							(mid -0.249642 -0.249642)
							(end -0.2794 -0.1778)
						)
						(arc
							(start -0.2794 0.1778)
							(mid -0.249642 0.249642)
							(end -0.1778 0.2794)
						)
						(arc
							(start 0.1778 0.2794)
							(mid 0.249642 0.249642)
							(end 0.2794 0.1778)
						)
						(arc
							(start 0.2794 -0.1778)
							(mid 0.249642 -0.249642)
							(end 0.1778 -0.2794)
						)
					)
					(width 0)
					(fill yes)
				)
			)
		)
		(pad "2" smd custom
			(at 0 0.4445 270)
			(size 0.1397 0.1397)
			(layers "F.Cu" "F.Mask" "F.Paste")
			(net "DEBUG_GPIO_BMC_4")
			(options
				(clearance outline)
				(anchor circle)
			)
			(primitives
				(gr_poly
					(pts
						(arc
							(start -0.1778 -0.2794)
							(mid -0.249642 -0.249642)
							(end -0.2794 -0.1778)
						)
						(arc
							(start -0.2794 0.1778)
							(mid -0.249642 0.249642)
							(end -0.1778 0.2794)
						)
						(arc
							(start 0.1778 0.2794)
							(mid 0.249642 0.249642)
							(end 0.2794 0.1778)
						)
						(arc
							(start 0.2794 -0.1778)
							(mid 0.249642 -0.249642)
							(end 0.1778 -0.2794)
						)
					)
					(width 0)
					(fill yes)
				)
			)
		)
	)
	(footprint ""
		(layer "F.Cu")
		(at 33.964372 -156.889958 -90)
		(property "Reference" "R320"
			(at 0 0 270)
			(layer "F.SilkS")
			(hide yes)
			(effects
				(font
					(size 1.27 1.27)
				)
			)
		)
		(property "Value" "0R2J-2-GP"
			(at 0.064008 -3.993896 270)
			(unlocked yes)
			(layer "F.Fab")
			(hide yes)
			(effects
				(font
					(size 1.016 1.016)
					(thickness 0.1524)
				)
			)
		)
		(property "Device Type" "R402H16"
			(at 0.064008 -5.517896 270)
			(unlocked yes)
			(layer "F.Fab")
			(hide yes)
			(effects
				(font
					(size 1.016 1.016)
					(thickness 0.1524)
				)
			)
		)
		(duplicate_pad_numbers_are_jumpers no)
		(fp_line
			(start -0.508 -0.9398)
			(end -0.508 0.9398)
			(stroke
				(width 0.1524)
				(type default)
			)
			(layer "F.SilkS")
		)
		(fp_line
			(start 0.508 -0.9398)
			(end -0.508 -0.9398)
			(stroke
				(width 0.1524)
				(type default)
			)
			(layer "F.SilkS")
		)
		(fp_rect
			(start -0.508 0.9398)
			(end 0.508 -0.9398)
			(stroke
				(width 0)
				(type default)
			)
			(fill no)
			(layer "F.CrtYd")
		)
		(fp_rect
			(start -0.508 0.9398)
			(end 0.508 -0.9398)
			(stroke
				(width 0)
				(type default)
			)
			(fill no)
			(layer "F.Fab")
		)
		(pad "1" smd custom
			(at 0 -0.4445 270)
			(size 0.1397 0.1397)
			(layers "F.Cu" "F.Mask" "F.Paste")
			(net "SCC_A_HB_IN_R")
			(options
				(clearance outline)
				(anchor circle)
			)
			(primitives
				(gr_poly
					(pts
						(arc
							(start -0.1778 -0.2794)
							(mid -0.249642 -0.249642)
							(end -0.2794 -0.1778)
						)
						(arc
							(start -0.2794 0.1778)
							(mid -0.249642 0.249642)
							(end -0.1778 0.2794)
						)
						(arc
							(start 0.1778 0.2794)
							(mid 0.249642 0.249642)
							(end 0.2794 0.1778)
						)
						(arc
							(start 0.2794 -0.1778)
							(mid 0.249642 -0.249642)
							(end 0.1778 -0.2794)
						)
					)
					(width 0)
					(fill yes)
				)
			)
		)
		(pad "2" smd custom
			(at 0 0.4445 270)
			(size 0.1397 0.1397)
			(layers "F.Cu" "F.Mask" "F.Paste")
			(net "SCC_LOC_HEARTBEAT")
			(options
				(clearance outline)
				(anchor circle)
			)
			(primitives
				(gr_poly
					(pts
						(arc
							(start -0.1778 -0.2794)
							(mid -0.249642 -0.249642)
							(end -0.2794 -0.1778)
						)
						(arc
							(start -0.2794 0.1778)
							(mid -0.249642 0.249642)
							(end -0.1778 0.2794)
						)
						(arc
							(start 0.1778 0.2794)
							(mid 0.249642 0.249642)
							(end 0.2794 0.1778)
						)
						(arc
							(start 0.2794 -0.1778)
							(mid 0.249642 -0.249642)
							(end 0.1778 -0.2794)
						)
					)
					(width 0)
					(fill yes)
				)
			)
		)
	)
	(footprint ""
		(layer "F.Cu")
		(at 64.3382 -149.9108 90)
		(property "Reference" "C82"
			(at 0 0 90)
			(layer "F.SilkS")
			(hide yes)
			(effects
				(font
					(size 1.27 1.27)
				)
			)
		)
		(property "Value" "SC33P50V2JN-3GP"
			(at 1.180846 -2.7051 90)
			(unlocked yes)
			(layer "F.Fab")
			(hide yes)
			(effects
				(font
					(size 1.016 1.016)
					(thickness 0.1524)
				)
			)
		)
		(property "Device Type" "C402H22"
			(at 1.180846 -4.228846 90)
			(unlocked yes)
			(layer "F.Fab")
			(hide yes)
			(effects
				(font
					(size 1.016 1.016)
					(thickness 0.1524)
				)
			)
		)
		(duplicate_pad_numbers_are_jumpers no)
		(fp_rect
			(start -0.4318 0.9525)
			(end 0.4318 -0.9525)
			(stroke
				(width 0)
				(type default)
			)
			(fill no)
			(layer "F.CrtYd")
		)
		(fp_rect
			(start -0.4318 0.9525)
			(end 0.4318 -0.9525)
			(stroke
				(width 0)
				(type default)
			)
			(fill no)
			(layer "F.Fab")
		)
		(pad "1" smd custom
			(at 0 -0.4445 90)
			(size 0.1524 0.1524)
			(layers "F.Cu" "F.Mask" "F.Paste")
			(net "PD_USB2AVRES")
			(options
				(clearance outline)
				(anchor circle)
			)
			(primitives
				(gr_poly
					(pts
						(arc
							(start 0.3048 -0.2032)
							(mid 0.275042 -0.275042)
							(end 0.2032 -0.3048)
						)
						(arc
							(start -0.2032 -0.3048)
							(mid -0.275042 -0.275042)
							(end -0.3048 -0.2032)
						)
						(arc
							(start -0.3048 0.2032)
							(mid -0.275042 0.275042)
							(end -0.2032 0.3048)
						)
						(arc
							(start 0.2032 0.3048)
							(mid 0.275042 0.275042)
							(end 0.3048 0.2032)
						)
					)
					(width 0)
					(fill yes)
				)
			)
		)
		(pad "2" smd custom
			(at 0 0.4445 90)
			(size 0.1524 0.1524)
			(layers "F.Cu" "F.Mask" "F.Paste")
			(net "GND")
			(options
				(clearance outline)
				(anchor circle)
			)
			(primitives
				(gr_poly
					(pts
						(arc
							(start 0.3048 -0.2032)
							(mid 0.275042 -0.275042)
							(end 0.2032 -0.3048)
						)
						(arc
							(start -0.2032 -0.3048)
							(mid -0.275042 -0.275042)
							(end -0.3048 -0.2032)
						)
						(arc
							(start -0.3048 0.2032)
							(mid -0.275042 0.275042)
							(end -0.2032 0.3048)
						)
						(arc
							(start 0.2032 0.3048)
							(mid 0.275042 0.275042)
							(end 0.3048 0.2032)
						)
					)
					(width 0)
					(fill yes)
				)
			)
		)
	)
)
